(kicad_pcb
	(version 20260206)
	(generator "pcbnew")
	(generator_version "10.0")
	(general
		(thickness 1.6)
		(legacy_teardrops no)
	)
	(paper "A4")
	(title_block
		(title "Bryce Canyon_SCC_16316-1_OCP.brd")
		(comment 1 "Bryce Canyon / footprints 283-290 of 1561")
	)
	(layers
		(0 "F.Cu" signal "TOP")
		(4 "In1.Cu" signal "L2GND")
		(6 "In2.Cu" signal "L3")
		(8 "In3.Cu" signal "L4VCC")
		(10 "In4.Cu" signal "L5VCC")
		(12 "In5.Cu" signal "L6")
		(14 "In6.Cu" signal "L7GND")
		(2 "B.Cu" signal "BOTTOM")
		(9 "F.Adhes" user "F.Adhesive")
		(11 "B.Adhes" user "B.Adhesive")
		(13 "F.Paste" user "Package Geometry/Pastemask Top")
		(15 "B.Paste" user "Package Geometry/Pastemask Bottom")
		(5 "F.SilkS" user "Ref Des/Silkscreen Top")
		(7 "B.SilkS" user "Ref Des/Silkscreen Bottom")
		(1 "F.Mask" user "Board Geometry/Soldermask Top")
		(3 "B.Mask" user "Board Geometry/Soldermask Bottom")
		(17 "Dwgs.User" user "User.Drawings")
		(19 "Cmts.User" user "User.Comments")
		(21 "Eco1.User" user "User.Eco1")
		(23 "Eco2.User" user "User.Eco2")
		(25 "Edge.Cuts" user "Board Geometry/Outline")
		(27 "Margin" user)
		(31 "F.CrtYd" user "Package Geometry/Place Bound Top")
		(29 "B.CrtYd" user "Package Geometry/Place Bound Bottom")
		(35 "F.Fab" user "Ref Des/Assembly Top")
		(33 "B.Fab" user "Ref Des/Assembly Bottom")
	)
	(footprint ""
		(layer "F.Cu")
		(at 184.3405 -55.695088)
		(property "Reference" "R213"
			(at 0 0 0)
			(layer "F.SilkS")
			(hide yes)
			(effects
				(font
					(size 1.27 1.27)
				)
			)
		)
		(property "Value" "10KR2F-2-GP"
			(at 0.064008 -3.993896 0)
			(unlocked yes)
			(layer "F.Fab")
			(hide yes)
			(effects
				(font
					(size 1.016 1.016)
					(thickness 0.1524)
				)
			)
		)
		(property "Device Type" "R402H16"
			(at 0.064008 -5.517896 0)
			(unlocked yes)
			(layer "F.Fab")
			(hide yes)
			(effects
				(font
					(size 1.016 1.016)
					(thickness 0.1524)
				)
			)
		)
		(duplicate_pad_numbers_are_jumpers no)
		(fp_line
			(start -0.508 -0.9398)
			(end -0.508 0.9398)
			(stroke
				(width 0.1524)
				(type default)
			)
			(layer "F.SilkS")
		)
		(fp_line
			(start 0.508 -0.9398)
			(end -0.508 -0.9398)
			(stroke
				(width 0.1524)
				(type default)
			)
			(layer "F.SilkS")
		)
		(fp_rect
			(start -0.508 0.9398)
			(end 0.508 -0.9398)
			(stroke
				(width 0)
				(type default)
			)
			(fill no)
			(layer "F.CrtYd")
		)
		(fp_rect
			(start -0.508 0.9398)
			(end 0.508 -0.9398)
			(stroke
				(width 0)
				(type default)
			)
			(fill no)
			(layer "F.Fab")
		)
		(pad "1" smd custom
			(at 0 -0.4445)
			(size 0.1397 0.1397)
			(layers "F.Cu" "F.Mask" "F.Paste")
			(net "P1V8_C")
			(options
				(clearance outline)
				(anchor circle)
			)
			(primitives
				(gr_poly
					(pts
						(arc
							(start -0.1778 -0.2794)
							(mid -0.249642 -0.249642)
							(end -0.2794 -0.1778)
						)
						(arc
							(start -0.2794 0.1778)
							(mid -0.249642 0.249642)
							(end -0.1778 0.2794)
						)
						(arc
							(start 0.1778 0.2794)
							(mid 0.249642 0.249642)
							(end 0.2794 0.1778)
						)
						(arc
							(start 0.2794 -0.1778)
							(mid 0.249642 -0.249642)
							(end 0.1778 -0.2794)
						)
					)
					(width 0)
					(fill yes)
				)
			)
		)
		(pad "2" smd custom
			(at 0 0.4445)
			(size 0.1397 0.1397)
			(layers "F.Cu" "F.Mask" "F.Paste")
			(net "XM_ADDR_0")
			(options
				(clearance outline)
				(anchor circle)
			)
			(primitives
				(gr_poly
					(pts
						(arc
							(start -0.1778 -0.2794)
							(mid -0.249642 -0.249642)
							(end -0.2794 -0.1778)
						)
						(arc
							(start -0.2794 0.1778)
							(mid -0.249642 0.249642)
							(end -0.1778 0.2794)
						)
						(arc
							(start 0.1778 0.2794)
							(mid 0.249642 0.249642)
							(end 0.2794 0.1778)
						)
						(arc
							(start 0.2794 -0.1778)
							(mid 0.249642 -0.249642)
							(end 0.1778 -0.2794)
						)
					)
					(width 0)
					(fill yes)
				)
			)
		)
	)
	(footprint ""
		(layer "F.Cu")
		(at 70.485 -46.482 90)
		(property "Reference" "R164"
			(at 0 0 90)
			(layer "F.SilkS")
			(hide yes)
			(effects
				(font
					(size 1.27 1.27)
				)
			)
		)
		(property "Value" "D51R3F-2-GP"
			(at -0.0254 -2.5146 90)
			(unlocked yes)
			(layer "F.Fab")
			(hide yes)
			(effects
				(font
					(size 1.016 1.016)
					(thickness 0.1524)
				)
			)
		)
		(property "Device Type" "R603H22"
			(at -0.0254 -4.0386 90)
			(unlocked yes)
			(layer "F.Fab")
			(hide yes)
			(effects
				(font
					(size 1.016 1.016)
					(thickness 0.1524)
				)
			)
		)
		(duplicate_pad_numbers_are_jumpers no)
		(fp_line
			(start 0.2032 0)
			(end 0.4826 0)
			(stroke
				(width 0.2032)
				(type default)
			)
			(layer "F.SilkS")
		)
		(fp_line
			(start -0.4826 0)
			(end -0.2032 0)
			(stroke
				(width 0.2032)
				(type default)
			)
			(layer "F.SilkS")
		)
		(fp_rect
			(start -0.5842 1.3335)
			(end 0.5842 -1.3335)
			(stroke
				(width 0)
				(type default)
			)
			(fill no)
			(layer "F.CrtYd")
		)
		(fp_rect
			(start -0.5842 1.3335)
			(end 0.5842 -1.3335)
			(stroke
				(width 0)
				(type default)
			)
			(fill no)
			(layer "F.Fab")
		)
		(pad "1" smd custom
			(at 0 -0.762 90)
			(size 0.2159 0.2159)
			(layers "F.Cu" "F.Mask" "F.Paste")
			(net "P0V9")
			(options
				(clearance outline)
				(anchor circle)
			)
			(primitives
				(gr_poly
					(pts
						(arc
							(start -0.3302 -0.4318)
							(mid -0.402042 -0.402042)
							(end -0.4318 -0.3302)
						)
						(arc
							(start -0.4318 0.3302)
							(mid -0.402042 0.402042)
							(end -0.3302 0.4318)
						)
						(arc
							(start 0.3302 0.4318)
							(mid 0.402042 0.402042)
							(end 0.4318 0.3302)
						)
						(arc
							(start 0.4318 -0.3302)
							(mid 0.402042 -0.402042)
							(end 0.3302 -0.4318)
						)
					)
					(width 0)
					(fill yes)
				)
			)
		)
		(pad "2" smd custom
			(at 0 0.762 90)
			(size 0.2159 0.2159)
			(layers "F.Cu" "F.Mask" "F.Paste")
			(net "GB_VDDA")
			(options
				(clearance outline)
				(anchor circle)
			)
			(primitives
				(gr_poly
					(pts
						(arc
							(start -0.3302 -0.4318)
							(mid -0.402042 -0.402042)
							(end -0.4318 -0.3302)
						)
						(arc
							(start -0.4318 0.3302)
							(mid -0.402042 0.402042)
							(end -0.3302 0.4318)
						)
						(arc
							(start 0.3302 0.4318)
							(mid 0.402042 0.402042)
							(end 0.4318 0.3302)
						)
						(arc
							(start 0.4318 -0.3302)
							(mid 0.402042 -0.402042)
							(end 0.3302 -0.4318)
						)
					)
					(width 0)
					(fill yes)
				)
			)
		)
	)
	(footprint ""
		(layer "F.Cu")
		(at 75.438 -57.2389)
		(property "Reference" "C295"
			(at 0 0 0)
			(layer "F.SilkS")
			(hide yes)
			(effects
				(font
					(size 1.27 1.27)
				)
			)
		)
		(property "Value" "SC22U6D3V3MX-9-GP-U"
			(at 0 -2.8194 0)
			(unlocked yes)
			(layer "F.Fab")
			(hide yes)
			(effects
				(font
					(size 1.016 1.016)
					(thickness 0.1524)
				)
			)
		)
		(property "Device Type" "C603H40"
			(at 0 -4.3434 0)
			(unlocked yes)
			(layer "F.Fab")
			(hide yes)
			(effects
				(font
					(size 1.016 1.016)
					(thickness 0.1524)
				)
			)
		)
		(duplicate_pad_numbers_are_jumpers no)
		(fp_line
			(start 0.508 0)
			(end -0.508 0)
			(stroke
				(width 0.2032)
				(type default)
			)
			(layer "F.SilkS")
		)
		(fp_rect
			(start -0.5842 1.3335)
			(end 0.5842 -1.3335)
			(stroke
				(width 0)
				(type default)
			)
			(fill no)
			(layer "F.CrtYd")
		)
		(fp_rect
			(start -0.5842 1.3335)
			(end 0.5842 -1.3335)
			(stroke
				(width 0)
				(type default)
			)
			(fill no)
			(layer "F.Fab")
		)
		(pad "1" smd custom
			(at 0 -0.762)
			(size 0.2159 0.2159)
			(layers "F.Cu" "F.Mask" "F.Paste")
			(net "GB_VDDA")
			(options
				(clearance outline)
				(anchor circle)
			)
			(primitives
				(gr_poly
					(pts
						(arc
							(start -0.3302 -0.4318)
							(mid -0.402042 -0.402042)
							(end -0.4318 -0.3302)
						)
						(arc
							(start -0.4318 0.3302)
							(mid -0.402042 0.402042)
							(end -0.3302 0.4318)
						)
						(arc
							(start 0.3302 0.4318)
							(mid 0.402042 0.402042)
							(end 0.4318 0.3302)
						)
						(arc
							(start 0.4318 -0.3302)
							(mid 0.402042 -0.402042)
							(end 0.3302 -0.4318)
						)
					)
					(width 0)
					(fill yes)
				)
			)
		)
		(pad "2" smd custom
			(at 0 0.762)
			(size 0.2159 0.2159)
			(layers "F.Cu" "F.Mask" "F.Paste")
			(net "GND")
			(options
				(clearance outline)
				(anchor circle)
			)
			(primitives
				(gr_poly
					(pts
						(arc
							(start -0.3302 -0.4318)
							(mid -0.402042 -0.402042)
							(end -0.4318 -0.3302)
						)
						(arc
							(start -0.4318 0.3302)
							(mid -0.402042 0.402042)
							(end -0.3302 0.4318)
						)
						(arc
							(start 0.3302 0.4318)
							(mid 0.402042 0.402042)
							(end 0.4318 0.3302)
						)
						(arc
							(start 0.4318 -0.3302)
							(mid 0.402042 -0.402042)
							(end 0.3302 -0.4318)
						)
					)
					(width 0)
					(fill yes)
				)
			)
		)
	)
	(footprint ""
		(layer "F.Cu")
		(at 147.425918 -47.00524 -78)
		(property "Reference" "VIA22"
			(at 0 0 282)
			(layer "F.SilkS")
			(hide yes)
			(effects
				(font
					(size 1.27 1.27)
				)
			)
		)
		(property "Value" "100OHM-8L-1D6MM-L13-GP"
			(at 3.289386 0.0506 282)
			(unlocked yes)
			(layer "F.Fab")
			(hide yes)
			(effects
				(font
					(size 1.016 1.016)
					(thickness 0.1524)
				)
			)
		)
		(property "Device Type" "VIA-PCIE-4P-409091"
			(at 3.289207 -1.473208 282)
			(unlocked yes)
			(layer "F.Fab")
			(hide yes)
			(effects
				(font
					(size 1.016 1.016)
					(thickness 0.1524)
				)
			)
		)
		(duplicate_pad_numbers_are_jumpers no)
		(fp_poly
			(pts
				(xy -2.044719 -0.457296) (xy 2.04468 -0.457296) (xy 2.044681 0.457104) (xy -2.044719 0.457104)
			)
			(stroke
				(width 0)
				(type default)
			)
			(fill no)
			(layer "F.CrtYd")
		)
		(fp_poly
			(pts
				(xy -2.044719 -0.457296) (xy 2.04468 -0.457296) (xy 2.044681 0.457104) (xy -2.044719 0.457104)
			)
			(stroke
				(width 0)
				(type default)
			)
			(fill no)
			(layer "F.Fab")
		)
		(pad "1" thru_hole circle
			(at -1.5875 0 282)
			(size 0.508 0.508)
			(drill 0.254)
			(layers "*.Cu" "*.Mask")
			(remove_unused_layers no)
			(net "GND")
			(clearance 0.2032)
			(thermal_gap 0.2032)
		)
		(pad "2" thru_hole circle
			(at -0.5715 0.000001 282)
			(size 0.508 0.508)
			(drill 0.254)
			(layers "*.Cu" "*.Mask")
			(remove_unused_layers no)
			(net "PHY_SCC_TO_IOC_C_45_DP")
			(clearance 0.2032)
			(thermal_gap 0.2032)
		)
		(pad "3" thru_hole circle
			(at 0.5715 -0.000001 282)
			(size 0.508 0.508)
			(drill 0.254)
			(layers "*.Cu" "*.Mask")
			(remove_unused_layers no)
			(net "PHY_SCC_TO_IOC_C_45_DN")
			(clearance 0.2032)
			(thermal_gap 0.2032)
		)
		(pad "4" thru_hole circle
			(at 1.5875 0 282)
			(size 0.508 0.508)
			(drill 0.254)
			(layers "*.Cu" "*.Mask")
			(remove_unused_layers no)
			(net "GND")
			(clearance 0.2032)
			(thermal_gap 0.2032)
		)
	)
	(footprint ""
		(layer "F.Cu")
		(at 189.2808 -22.9616 -90)
		(property "Reference" "R248"
			(at 0 0 270)
			(layer "F.SilkS")
			(hide yes)
			(effects
				(font
					(size 1.27 1.27)
				)
			)
		)
		(property "Value" "4K7R2F-GP"
			(at 0.064008 -3.993896 270)
			(unlocked yes)
			(layer "F.Fab")
			(hide yes)
			(effects
				(font
					(size 1.016 1.016)
					(thickness 0.1524)
				)
			)
		)
		(property "Device Type" "R402H16"
			(at 0.064008 -5.517896 270)
			(unlocked yes)
			(layer "F.Fab")
			(hide yes)
			(effects
				(font
					(size 1.016 1.016)
					(thickness 0.1524)
				)
			)
		)
		(duplicate_pad_numbers_are_jumpers no)
		(fp_line
			(start -0.508 -0.9398)
			(end -0.508 0.9398)
			(stroke
				(width 0.1524)
				(type default)
			)
			(layer "F.SilkS")
		)
		(fp_line
			(start 0.508 -0.9398)
			(end -0.508 -0.9398)
			(stroke
				(width 0.1524)
				(type default)
			)
			(layer "F.SilkS")
		)
		(fp_rect
			(start -0.508 0.9398)
			(end 0.508 -0.9398)
			(stroke
				(width 0)
				(type default)
			)
			(fill no)
			(layer "F.CrtYd")
		)
		(fp_rect
			(start -0.508 0.9398)
			(end 0.508 -0.9398)
			(stroke
				(width 0)
				(type default)
			)
			(fill no)
			(layer "F.Fab")
		)
		(pad "1" smd custom
			(at 0 -0.4445 270)
			(size 0.1397 0.1397)
			(layers "F.Cu" "F.Mask" "F.Paste")
			(net "P1V8_C")
			(options
				(clearance outline)
				(anchor circle)
			)
			(primitives
				(gr_poly
					(pts
						(arc
							(start -0.1778 -0.2794)
							(mid -0.249642 -0.249642)
							(end -0.2794 -0.1778)
						)
						(arc
							(start -0.2794 0.1778)
							(mid -0.249642 0.249642)
							(end -0.1778 0.2794)
						)
						(arc
							(start 0.1778 0.2794)
							(mid 0.249642 0.249642)
							(end 0.2794 0.1778)
						)
						(arc
							(start 0.2794 -0.1778)
							(mid 0.249642 -0.249642)
							(end 0.1778 -0.2794)
						)
					)
					(width 0)
					(fill yes)
				)
			)
		)
		(pad "2" smd custom
			(at 0 0.4445 270)
			(size 0.1397 0.1397)
			(layers "F.Cu" "F.Mask" "F.Paste")
			(net "SYS_DBMODE3")
			(options
				(clearance outline)
				(anchor circle)
			)
			(primitives
				(gr_poly
					(pts
						(arc
							(start -0.1778 -0.2794)
							(mid -0.249642 -0.249642)
							(end -0.2794 -0.1778)
						)
						(arc
							(start -0.2794 0.1778)
							(mid -0.249642 0.249642)
							(end -0.1778 0.2794)
						)
						(arc
							(start 0.1778 0.2794)
							(mid 0.249642 0.249642)
							(end 0.2794 0.1778)
						)
						(arc
							(start 0.2794 -0.1778)
							(mid 0.249642 -0.249642)
							(end 0.1778 -0.2794)
						)
					)
					(width 0)
					(fill yes)
				)
			)
		)
	)
	(footprint ""
		(layer "F.Cu")
		(at 18.5674 -94.9452 180)
		(property "Reference" "R407"
			(at 0 0 180)
			(layer "F.SilkS")
			(hide yes)
			(effects
				(font
					(size 1.27 1.27)
				)
			)
		)
		(property "Value" "200KR2F-L-GP"
			(at 0.064008 -3.993896 180)
			(unlocked yes)
			(layer "F.Fab")
			(hide yes)
			(effects
				(font
					(size 1.016 1.016)
					(thickness 0.1524)
				)
			)
		)
		(property "Device Type" "R402H16"
			(at 0.064008 -5.517896 180)
			(unlocked yes)
			(layer "F.Fab")
			(hide yes)
			(effects
				(font
					(size 1.016 1.016)
					(thickness 0.1524)
				)
			)
		)
		(duplicate_pad_numbers_are_jumpers no)
		(fp_line
			(start 0.508 -0.9398)
			(end -0.508 -0.9398)
			(stroke
				(width 0.1524)
				(type default)
			)
			(layer "F.SilkS")
		)
		(fp_line
			(start -0.508 -0.9398)
			(end -0.508 0.9398)
			(stroke
				(width 0.1524)
				(type default)
			)
			(layer "F.SilkS")
		)
		(fp_rect
			(start -0.508 0.9398)
			(end 0.508 -0.9398)
			(stroke
				(width 0)
				(type default)
			)
			(fill no)
			(layer "F.CrtYd")
		)
		(fp_rect
			(start -0.508 0.9398)
			(end 0.508 -0.9398)
			(stroke
				(width 0)
				(type default)
			)
			(fill no)
			(layer "F.Fab")
		)
		(pad "1" smd custom
			(at 0 -0.4445 180)
			(size 0.1397 0.1397)
			(layers "F.Cu" "F.Mask" "F.Paste")
			(net "VREF0")
			(options
				(clearance outline)
				(anchor circle)
			)
			(primitives
				(gr_poly
					(pts
						(arc
							(start -0.1778 -0.2794)
							(mid -0.249642 -0.249642)
							(end -0.2794 -0.1778)
						)
						(arc
							(start -0.2794 0.1778)
							(mid -0.249642 0.249642)
							(end -0.1778 0.2794)
						)
						(arc
							(start 0.1778 0.2794)
							(mid 0.249642 0.249642)
							(end 0.2794 0.1778)
						)
						(arc
							(start 0.2794 -0.1778)
							(mid 0.249642 -0.249642)
							(end 0.1778 -0.2794)
						)
					)
					(width 0)
					(fill yes)
				)
			)
		)
		(pad "2" smd custom
			(at 0 0.4445 180)
			(size 0.1397 0.1397)
			(layers "F.Cu" "F.Mask" "F.Paste")
			(net "P3V3")
			(options
				(clearance outline)
				(anchor circle)
			)
			(primitives
				(gr_poly
					(pts
						(arc
							(start -0.1778 -0.2794)
							(mid -0.249642 -0.249642)
							(end -0.2794 -0.1778)
						)
						(arc
							(start -0.2794 0.1778)
							(mid -0.249642 0.249642)
							(end -0.1778 0.2794)
						)
						(arc
							(start 0.1778 0.2794)
							(mid 0.249642 0.249642)
							(end 0.2794 0.1778)
						)
						(arc
							(start 0.2794 -0.1778)
							(mid 0.249642 -0.249642)
							(end 0.1778 -0.2794)
						)
					)
					(width 0)
					(fill yes)
				)
			)
		)
	)
	(footprint ""
		(layer "F.Cu")
		(at 76.12634 -71.404988 90)
		(property "Reference" "R540"
			(at 0 0 90)
			(layer "F.SilkS")
			(hide yes)
			(effects
				(font
					(size 1.27 1.27)
				)
			)
		)
		(property "Value" "0R2J-2-GP"
			(at 0.064008 -3.993896 90)
			(unlocked yes)
			(layer "F.Fab")
			(hide yes)
			(effects
				(font
					(size 1.016 1.016)
					(thickness 0.1524)
				)
			)
		)
		(property "Device Type" "R402H16"
			(at 0.064008 -5.517896 90)
			(unlocked yes)
			(layer "F.Fab")
			(hide yes)
			(effects
				(font
					(size 1.016 1.016)
					(thickness 0.1524)
				)
			)
		)
		(duplicate_pad_numbers_are_jumpers no)
		(fp_line
			(start 0.508 -0.9398)
			(end -0.508 -0.9398)
			(stroke
				(width 0.1524)
				(type default)
			)
			(layer "F.SilkS")
		)
		(fp_line
			(start -0.508 -0.9398)
			(end -0.508 0.9398)
			(stroke
				(width 0.1524)
				(type default)
			)
			(layer "F.SilkS")
		)
		(fp_rect
			(start -0.508 0.9398)
			(end 0.508 -0.9398)
			(stroke
				(width 0)
				(type default)
			)
			(fill no)
			(layer "F.CrtYd")
		)
		(fp_rect
			(start -0.508 0.9398)
			(end 0.508 -0.9398)
			(stroke
				(width 0)
				(type default)
			)
			(fill no)
			(layer "F.Fab")
		)
		(pad "1" smd custom
			(at 0 -0.4445 90)
			(size 0.1397 0.1397)
			(layers "F.Cu" "F.Mask" "F.Paste")
			(net "I2C_IOC_4_R_SCL")
			(options
				(clearance outline)
				(anchor circle)
			)
			(primitives
				(gr_poly
					(pts
						(arc
							(start -0.1778 -0.2794)
							(mid -0.249642 -0.249642)
							(end -0.2794 -0.1778)
						)
						(arc
							(start -0.2794 0.1778)
							(mid -0.249642 0.249642)
							(end -0.1778 0.2794)
						)
						(arc
							(start 0.1778 0.2794)
							(mid 0.249642 0.249642)
							(end 0.2794 0.1778)
						)
						(arc
							(start 0.2794 -0.1778)
							(mid 0.249642 -0.249642)
							(end 0.1778 -0.2794)
						)
					)
					(width 0)
					(fill yes)
				)
			)
		)
		(pad "2" smd custom
			(at 0 0.4445 90)
			(size 0.1397 0.1397)
			(layers "F.Cu" "F.Mask" "F.Paste")
			(net "I2C_IOC_4_SCL")
			(options
				(clearance outline)
				(anchor circle)
			)
			(primitives
				(gr_poly
					(pts
						(arc
							(start -0.1778 -0.2794)
							(mid -0.249642 -0.249642)
							(end -0.2794 -0.1778)
						)
						(arc
							(start -0.2794 0.1778)
							(mid -0.249642 0.249642)
							(end -0.1778 0.2794)
						)
						(arc
							(start 0.1778 0.2794)
							(mid 0.249642 0.249642)
							(end 0.2794 0.1778)
						)
						(arc
							(start 0.2794 -0.1778)
							(mid 0.249642 -0.249642)
							(end 0.1778 -0.2794)
						)
					)
					(width 0)
					(fill yes)
				)
			)
		)
	)
	(footprint ""
		(layer "F.Cu")
		(at 123.317 -108.59008)
		(property "Reference" "TP153"
			(at 0 0 0)
			(layer "F.SilkS")
			(hide yes)
			(effects
				(font
					(size 1.27 1.27)
				)
			)
		)
		(property "Value" "TPAD28-2-GP"
			(at -0.0127 -1.6637 0)
			(unlocked yes)
			(layer "F.Fab")
			(hide yes)
			(effects
				(font
					(size 1.016 1.016)
					(thickness 0.1524)
				)
			)
		)
		(property "Device Type" "TPAD28"
			(at -0.0127 -3.1877 0)
			(unlocked yes)
			(layer "F.Fab")
			(hide yes)
			(effects
				(font
					(size 1.016 1.016)
					(thickness 0.1524)
				)
			)
		)
		(duplicate_pad_numbers_are_jumpers no)
		(fp_poly
			(pts
				(arc
					(start 0.3556 0)
					(mid -0.3556 0)
					(end 0.3556 0)
				)
			)
			(stroke
				(width 0)
				(type default)
			)
			(fill no)
			(layer "F.CrtYd")
		)
		(fp_poly
			(pts
				(arc
					(start 0.6096 0)
					(mid -0.6096 0)
					(end 0.6096 0)
				)
			)
			(stroke
				(width 0)
				(type default)
			)
			(fill no)
			(layer "F.Fab")
		)
		(pad "1" smd circle
			(at 0 0)
			(size 0.7112 0.7112)
			(layers "F.Cu" "F.Mask" "F.Paste")
			(net "INT_D1_CONN1")
		)
	)
)
